(kicad_pcb
	(version 20260206)
	(generator "pcbnew")
	(generator_version "10.0")
	(general
		(thickness 1.6)
		(legacy_teardrops no)
	)
	(paper "A4")
	(title_block
		(title "pdpb — Lightning_PDPB_BRD.brd")
		(comment 1 "Lightning (Wiwynn / Facebook NVMe JBOF) / footprints 738-744 of 1140")
	)
	(layers
		(0 "F.Cu" signal "TOP")
		(4 "In1.Cu" signal "L2GND")
		(6 "In2.Cu" signal "L3")
		(8 "In3.Cu" signal "L4VCC")
		(10 "In4.Cu" signal "L5VCC")
		(12 "In5.Cu" signal "L6")
		(14 "In6.Cu" signal "L7GND")
		(2 "B.Cu" signal "BOTTOM")
		(9 "F.Adhes" user "F.Adhesive")
		(11 "B.Adhes" user "B.Adhesive")
		(13 "F.Paste" user "Package Geometry/Pastemask Top")
		(15 "B.Paste" user "Package Geometry/Pastemask Bottom")
		(5 "F.SilkS" user "Ref Des/Silkscreen Top")
		(7 "B.SilkS" user "Ref Des/Silkscreen Bottom")
		(1 "F.Mask" user "Board Geometry/Soldermask Top")
		(3 "B.Mask" user "Board Geometry/Soldermask Bottom")
		(17 "Dwgs.User" user "User.Drawings")
		(19 "Cmts.User" user "User.Comments")
		(21 "Eco1.User" user "User.Eco1")
		(23 "Eco2.User" user "User.Eco2")
		(25 "Edge.Cuts" user "Board Geometry/Outline")
		(27 "Margin" user)
		(31 "F.CrtYd" user "Package Geometry/Place Bound Top")
		(29 "B.CrtYd" user "Package Geometry/Place Bound Bottom")
		(35 "F.Fab" user "Ref Des/Assembly Top")
		(33 "B.Fab" user "Ref Des/Assembly Bottom")
	)
	(footprint ""
		(layer "F.Cu")
		(at 71.247 -440.182)
		(property "Reference" "R351"
			(at 0 0 0)
			(layer "F.SilkS")
			(hide yes)
			(effects
				(font
					(size 1.27 1.27)
				)
			)
		)
		(property "Value" "0R2J-2-GP"
			(at 0.064008 -3.993896 0)
			(unlocked yes)
			(layer "F.Fab")
			(hide yes)
			(effects
				(font
					(size 1.016 1.016)
					(thickness 0.1524)
				)
			)
		)
		(property "Device Type" "R402H16"
			(at 0.064008 -5.517896 0)
			(unlocked yes)
			(layer "F.Fab")
			(hide yes)
			(effects
				(font
					(size 1.016 1.016)
					(thickness 0.1524)
				)
			)
		)
		(duplicate_pad_numbers_are_jumpers no)
		(fp_line
			(start -0.508 -0.9398)
			(end -0.508 0.9398)
			(stroke
				(width 0.1524)
				(type default)
			)
			(layer "F.SilkS")
		)
		(fp_line
			(start 0.508 -0.9398)
			(end -0.508 -0.9398)
			(stroke
				(width 0.1524)
				(type default)
			)
			(layer "F.SilkS")
		)
		(fp_rect
			(start -0.508 0.9398)
			(end 0.508 -0.9398)
			(stroke
				(width 0)
				(type default)
			)
			(fill no)
			(layer "F.CrtYd")
		)
		(fp_rect
			(start -0.508 0.9398)
			(end 0.508 -0.9398)
			(stroke
				(width 0)
				(type default)
			)
			(fill no)
			(layer "F.Fab")
		)
		(pad "1" smd custom
			(at 0 -0.4445)
			(size 0.1397 0.1397)
			(layers "F.Cu" "F.Mask" "F.Paste")
			(net "EEPROM_WP")
			(options
				(clearance outline)
				(anchor circle)
			)
			(primitives
				(gr_poly
					(pts
						(arc
							(start -0.1778 -0.2794)
							(mid -0.249642 -0.249642)
							(end -0.2794 -0.1778)
						)
						(arc
							(start -0.2794 0.1778)
							(mid -0.249642 0.249642)
							(end -0.1778 0.2794)
						)
						(arc
							(start 0.1778 0.2794)
							(mid 0.249642 0.249642)
							(end 0.2794 0.1778)
						)
						(arc
							(start 0.2794 -0.1778)
							(mid 0.249642 -0.249642)
							(end 0.1778 -0.2794)
						)
					)
					(width 0)
					(fill yes)
				)
			)
		)
		(pad "2" smd custom
			(at 0 0.4445)
			(size 0.1397 0.1397)
			(layers "F.Cu" "F.Mask" "F.Paste")
			(net "GND")
			(options
				(clearance outline)
				(anchor circle)
			)
			(primitives
				(gr_poly
					(pts
						(arc
							(start -0.1778 -0.2794)
							(mid -0.249642 -0.249642)
							(end -0.2794 -0.1778)
						)
						(arc
							(start -0.2794 0.1778)
							(mid -0.249642 0.249642)
							(end -0.1778 0.2794)
						)
						(arc
							(start 0.1778 0.2794)
							(mid 0.249642 0.249642)
							(end 0.2794 0.1778)
						)
						(arc
							(start 0.2794 -0.1778)
							(mid 0.249642 -0.249642)
							(end 0.1778 -0.2794)
						)
					)
					(width 0)
					(fill yes)
				)
			)
		)
	)
	(footprint ""
		(layer "F.Cu")
		(at 95.504 -313.817 180)
		(property "Reference" "R9099"
			(at 0 0 180)
			(layer "F.SilkS")
			(hide yes)
			(effects
				(font
					(size 1.27 1.27)
				)
			)
		)
		(property "Value" "27R2F-GP"
			(at 0.064008 -3.993896 180)
			(unlocked yes)
			(layer "F.Fab")
			(hide yes)
			(effects
				(font
					(size 1.016 1.016)
					(thickness 0.1524)
				)
			)
		)
		(property "Device Type" "R402H16"
			(at 0.064008 -5.517896 180)
			(unlocked yes)
			(layer "F.Fab")
			(hide yes)
			(effects
				(font
					(size 1.016 1.016)
					(thickness 0.1524)
				)
			)
		)
		(duplicate_pad_numbers_are_jumpers no)
		(fp_line
			(start 0.508 -0.9398)
			(end -0.508 -0.9398)
			(stroke
				(width 0.1524)
				(type default)
			)
			(layer "F.SilkS")
		)
		(fp_line
			(start -0.508 -0.9398)
			(end -0.508 0.9398)
			(stroke
				(width 0.1524)
				(type default)
			)
			(layer "F.SilkS")
		)
		(fp_rect
			(start -0.508 0.9398)
			(end 0.508 -0.9398)
			(stroke
				(width 0)
				(type default)
			)
			(fill no)
			(layer "F.CrtYd")
		)
		(fp_rect
			(start -0.508 0.9398)
			(end 0.508 -0.9398)
			(stroke
				(width 0)
				(type default)
			)
			(fill no)
			(layer "F.Fab")
		)
		(pad "1" smd custom
			(at 0 -0.4445 180)
			(size 0.1397 0.1397)
			(layers "F.Cu" "F.Mask" "F.Paste")
			(net "PE_CLK_100M_DR6_1_R_N")
			(options
				(clearance outline)
				(anchor circle)
			)
			(primitives
				(gr_poly
					(pts
						(arc
							(start -0.1778 -0.2794)
							(mid -0.249642 -0.249642)
							(end -0.2794 -0.1778)
						)
						(arc
							(start -0.2794 0.1778)
							(mid -0.249642 0.249642)
							(end -0.1778 0.2794)
						)
						(arc
							(start 0.1778 0.2794)
							(mid 0.249642 0.249642)
							(end 0.2794 0.1778)
						)
						(arc
							(start 0.2794 -0.1778)
							(mid 0.249642 -0.249642)
							(end 0.1778 -0.2794)
						)
					)
					(width 0)
					(fill yes)
				)
			)
		)
		(pad "2" smd custom
			(at 0 0.4445 180)
			(size 0.1397 0.1397)
			(layers "F.Cu" "F.Mask" "F.Paste")
			(net "PE_CLK100M_DR6_1_N")
			(options
				(clearance outline)
				(anchor circle)
			)
			(primitives
				(gr_poly
					(pts
						(arc
							(start -0.1778 -0.2794)
							(mid -0.249642 -0.249642)
							(end -0.2794 -0.1778)
						)
						(arc
							(start -0.2794 0.1778)
							(mid -0.249642 0.249642)
							(end -0.1778 0.2794)
						)
						(arc
							(start 0.1778 0.2794)
							(mid 0.249642 0.249642)
							(end 0.2794 0.1778)
						)
						(arc
							(start 0.2794 -0.1778)
							(mid 0.249642 -0.249642)
							(end 0.1778 -0.2794)
						)
					)
					(width 0)
					(fill yes)
				)
			)
		)
	)
	(footprint ""
		(layer "F.Cu")
		(at 37.973 -308.737 180)
		(property "Reference" "R9771"
			(at 0 0 180)
			(layer "F.SilkS")
			(hide yes)
			(effects
				(font
					(size 1.27 1.27)
				)
			)
		)
		(property "Value" "4K7R2J-2-GP"
			(at 0.064008 -3.993896 180)
			(unlocked yes)
			(layer "F.Fab")
			(hide yes)
			(effects
				(font
					(size 1.016 1.016)
					(thickness 0.1524)
				)
			)
		)
		(property "Device Type" "R402H16"
			(at 0.064008 -5.517896 180)
			(unlocked yes)
			(layer "F.Fab")
			(hide yes)
			(effects
				(font
					(size 1.016 1.016)
					(thickness 0.1524)
				)
			)
		)
		(duplicate_pad_numbers_are_jumpers no)
		(fp_line
			(start 0.508 -0.9398)
			(end -0.508 -0.9398)
			(stroke
				(width 0.1524)
				(type default)
			)
			(layer "F.SilkS")
		)
		(fp_line
			(start -0.508 -0.9398)
			(end -0.508 0.9398)
			(stroke
				(width 0.1524)
				(type default)
			)
			(layer "F.SilkS")
		)
		(fp_rect
			(start -0.508 0.9398)
			(end 0.508 -0.9398)
			(stroke
				(width 0)
				(type default)
			)
			(fill no)
			(layer "F.CrtYd")
		)
		(fp_rect
			(start -0.508 0.9398)
			(end 0.508 -0.9398)
			(stroke
				(width 0)
				(type default)
			)
			(fill no)
			(layer "F.Fab")
		)
		(pad "1" smd custom
			(at 0 -0.4445 180)
			(size 0.1397 0.1397)
			(layers "F.Cu" "F.Mask" "F.Paste")
			(net "SSD11_PWREN")
			(options
				(clearance outline)
				(anchor circle)
			)
			(primitives
				(gr_poly
					(pts
						(arc
							(start -0.1778 -0.2794)
							(mid -0.249642 -0.249642)
							(end -0.2794 -0.1778)
						)
						(arc
							(start -0.2794 0.1778)
							(mid -0.249642 0.249642)
							(end -0.1778 0.2794)
						)
						(arc
							(start 0.1778 0.2794)
							(mid 0.249642 0.249642)
							(end 0.2794 0.1778)
						)
						(arc
							(start 0.2794 -0.1778)
							(mid 0.249642 -0.249642)
							(end 0.1778 -0.2794)
						)
					)
					(width 0)
					(fill yes)
				)
			)
		)
		(pad "2" smd custom
			(at 0 0.4445 180)
			(size 0.1397 0.1397)
			(layers "F.Cu" "F.Mask" "F.Paste")
			(net "GND")
			(options
				(clearance outline)
				(anchor circle)
			)
			(primitives
				(gr_poly
					(pts
						(arc
							(start -0.1778 -0.2794)
							(mid -0.249642 -0.249642)
							(end -0.2794 -0.1778)
						)
						(arc
							(start -0.2794 0.1778)
							(mid -0.249642 0.249642)
							(end -0.1778 0.2794)
						)
						(arc
							(start 0.1778 0.2794)
							(mid 0.249642 0.249642)
							(end 0.2794 0.1778)
						)
						(arc
							(start 0.2794 -0.1778)
							(mid 0.249642 -0.249642)
							(end 0.1778 -0.2794)
						)
					)
					(width 0)
					(fill yes)
				)
			)
		)
	)
	(footprint ""
		(layer "F.Cu")
		(at 208.153 -293.116)
		(property "Reference" "R553"
			(at 0 0 0)
			(layer "F.SilkS")
			(hide yes)
			(effects
				(font
					(size 1.27 1.27)
				)
			)
		)
		(property "Value" "200KR2F-L-GP"
			(at 0.064008 -3.993896 0)
			(unlocked yes)
			(layer "F.Fab")
			(hide yes)
			(effects
				(font
					(size 1.016 1.016)
					(thickness 0.1524)
				)
			)
		)
		(property "Device Type" "R402H16"
			(at 0.064008 -5.517896 0)
			(unlocked yes)
			(layer "F.Fab")
			(hide yes)
			(effects
				(font
					(size 1.016 1.016)
					(thickness 0.1524)
				)
			)
		)
		(duplicate_pad_numbers_are_jumpers no)
		(fp_line
			(start -0.508 -0.9398)
			(end -0.508 0.9398)
			(stroke
				(width 0.1524)
				(type default)
			)
			(layer "F.SilkS")
		)
		(fp_line
			(start 0.508 -0.9398)
			(end -0.508 -0.9398)
			(stroke
				(width 0.1524)
				(type default)
			)
			(layer "F.SilkS")
		)
		(fp_rect
			(start -0.508 0.9398)
			(end 0.508 -0.9398)
			(stroke
				(width 0)
				(type default)
			)
			(fill no)
			(layer "F.CrtYd")
		)
		(fp_rect
			(start -0.508 0.9398)
			(end 0.508 -0.9398)
			(stroke
				(width 0)
				(type default)
			)
			(fill no)
			(layer "F.Fab")
		)
		(pad "1" smd custom
			(at 0 -0.4445)
			(size 0.1397 0.1397)
			(layers "F.Cu" "F.Mask" "F.Paste")
			(net "SW_SSD2_R")
			(options
				(clearance outline)
				(anchor circle)
			)
			(primitives
				(gr_poly
					(pts
						(arc
							(start -0.1778 -0.2794)
							(mid -0.249642 -0.249642)
							(end -0.2794 -0.1778)
						)
						(arc
							(start -0.2794 0.1778)
							(mid -0.249642 0.249642)
							(end -0.1778 0.2794)
						)
						(arc
							(start 0.1778 0.2794)
							(mid 0.249642 0.249642)
							(end 0.2794 0.1778)
						)
						(arc
							(start 0.2794 -0.1778)
							(mid 0.249642 -0.249642)
							(end 0.1778 -0.2794)
						)
					)
					(width 0)
					(fill yes)
				)
			)
		)
		(pad "2" smd custom
			(at 0 0.4445)
			(size 0.1397 0.1397)
			(layers "F.Cu" "F.Mask" "F.Paste")
			(net "SW_SSD2_N")
			(options
				(clearance outline)
				(anchor circle)
			)
			(primitives
				(gr_poly
					(pts
						(arc
							(start -0.1778 -0.2794)
							(mid -0.249642 -0.249642)
							(end -0.2794 -0.1778)
						)
						(arc
							(start -0.2794 0.1778)
							(mid -0.249642 0.249642)
							(end -0.1778 0.2794)
						)
						(arc
							(start 0.1778 0.2794)
							(mid 0.249642 0.249642)
							(end 0.2794 0.1778)
						)
						(arc
							(start 0.2794 -0.1778)
							(mid 0.249642 -0.249642)
							(end 0.1778 -0.2794)
						)
					)
					(width 0)
					(fill yes)
				)
			)
		)
	)
	(footprint ""
		(layer "F.Cu")
		(at 23.495 -153.67 180)
		(property "Reference" "R9905"
			(at 0 0 180)
			(layer "F.SilkS")
			(hide yes)
			(effects
				(font
					(size 1.27 1.27)
				)
			)
		)
		(property "Value" "1K82R2F-1-GP"
			(at 0.064008 -3.993896 180)
			(unlocked yes)
			(layer "F.Fab")
			(hide yes)
			(effects
				(font
					(size 1.016 1.016)
					(thickness 0.1524)
				)
			)
		)
		(property "Device Type" "R402H16"
			(at 0.064008 -5.517896 180)
			(unlocked yes)
			(layer "F.Fab")
			(hide yes)
			(effects
				(font
					(size 1.016 1.016)
					(thickness 0.1524)
				)
			)
		)
		(duplicate_pad_numbers_are_jumpers no)
		(fp_line
			(start 0.508 -0.9398)
			(end -0.508 -0.9398)
			(stroke
				(width 0.1524)
				(type default)
			)
			(layer "F.SilkS")
		)
		(fp_line
			(start -0.508 -0.9398)
			(end -0.508 0.9398)
			(stroke
				(width 0.1524)
				(type default)
			)
			(layer "F.SilkS")
		)
		(fp_rect
			(start -0.508 0.9398)
			(end 0.508 -0.9398)
			(stroke
				(width 0)
				(type default)
			)
			(fill no)
			(layer "F.CrtYd")
		)
		(fp_rect
			(start -0.508 0.9398)
			(end 0.508 -0.9398)
			(stroke
				(width 0)
				(type default)
			)
			(fill no)
			(layer "F.Fab")
		)
		(pad "1" smd custom
			(at 0 -0.4445 180)
			(size 0.1397 0.1397)
			(layers "F.Cu" "F.Mask" "F.Paste")
			(net "P12V")
			(options
				(clearance outline)
				(anchor circle)
			)
			(primitives
				(gr_poly
					(pts
						(arc
							(start -0.1778 -0.2794)
							(mid -0.249642 -0.249642)
							(end -0.2794 -0.1778)
						)
						(arc
							(start -0.2794 0.1778)
							(mid -0.249642 0.249642)
							(end -0.1778 0.2794)
						)
						(arc
							(start 0.1778 0.2794)
							(mid 0.249642 0.249642)
							(end 0.2794 0.1778)
						)
						(arc
							(start 0.2794 -0.1778)
							(mid 0.249642 -0.249642)
							(end 0.1778 -0.2794)
						)
					)
					(width 0)
					(fill yes)
				)
			)
		)
		(pad "2" smd custom
			(at 0 0.4445 180)
			(size 0.1397 0.1397)
			(layers "F.Cu" "F.Mask" "F.Paste")
			(net "DRV_ACT_13")
			(options
				(clearance outline)
				(anchor circle)
			)
			(primitives
				(gr_poly
					(pts
						(arc
							(start -0.1778 -0.2794)
							(mid -0.249642 -0.249642)
							(end -0.2794 -0.1778)
						)
						(arc
							(start -0.2794 0.1778)
							(mid -0.249642 0.249642)
							(end -0.1778 0.2794)
						)
						(arc
							(start 0.1778 0.2794)
							(mid 0.249642 0.249642)
							(end 0.2794 0.1778)
						)
						(arc
							(start 0.2794 -0.1778)
							(mid 0.249642 -0.249642)
							(end 0.1778 -0.2794)
						)
					)
					(width 0)
					(fill yes)
				)
			)
		)
	)
	(footprint ""
		(layer "F.Cu")
		(at 81.661 -365.1758 -90)
		(property "Reference" "SR989"
			(at 0 0 270)
			(layer "F.SilkS")
			(hide yes)
			(effects
				(font
					(size 1.27 1.27)
				)
			)
		)
		(property "Value" "2KR2F-3-GP"
			(at 0.064008 -3.993896 270)
			(unlocked yes)
			(layer "F.Fab")
			(hide yes)
			(effects
				(font
					(size 1.016 1.016)
					(thickness 0.1524)
				)
			)
		)
		(property "Device Type" "R402H16"
			(at 0.064008 -5.517896 270)
			(unlocked yes)
			(layer "F.Fab")
			(hide yes)
			(effects
				(font
					(size 1.016 1.016)
					(thickness 0.1524)
				)
			)
		)
		(duplicate_pad_numbers_are_jumpers no)
		(fp_line
			(start -0.508 -0.9398)
			(end -0.508 0.9398)
			(stroke
				(width 0.1524)
				(type default)
			)
			(layer "F.SilkS")
		)
		(fp_line
			(start 0.508 -0.9398)
			(end -0.508 -0.9398)
			(stroke
				(width 0.1524)
				(type default)
			)
			(layer "F.SilkS")
		)
		(fp_rect
			(start -0.508 0.9398)
			(end 0.508 -0.9398)
			(stroke
				(width 0)
				(type default)
			)
			(fill no)
			(layer "F.CrtYd")
		)
		(fp_rect
			(start -0.508 0.9398)
			(end 0.508 -0.9398)
			(stroke
				(width 0)
				(type default)
			)
			(fill no)
			(layer "F.Fab")
		)
		(pad "1" smd custom
			(at 0 -0.4445 270)
			(size 0.1397 0.1397)
			(layers "F.Cu" "F.Mask" "F.Paste")
			(net "P3V3")
			(options
				(clearance outline)
				(anchor circle)
			)
			(primitives
				(gr_poly
					(pts
						(arc
							(start -0.1778 -0.2794)
							(mid -0.249642 -0.249642)
							(end -0.2794 -0.1778)
						)
						(arc
							(start -0.2794 0.1778)
							(mid -0.249642 0.249642)
							(end -0.1778 0.2794)
						)
						(arc
							(start 0.1778 0.2794)
							(mid 0.249642 0.249642)
							(end 0.2794 0.1778)
						)
						(arc
							(start 0.2794 -0.1778)
							(mid 0.249642 -0.249642)
							(end 0.1778 -0.2794)
						)
					)
					(width 0)
					(fill yes)
				)
			)
		)
		(pad "2" smd custom
			(at 0 0.4445 270)
			(size 0.1397 0.1397)
			(layers "F.Cu" "F.Mask" "F.Paste")
			(net "SCL_DR0")
			(options
				(clearance outline)
				(anchor circle)
			)
			(primitives
				(gr_poly
					(pts
						(arc
							(start -0.1778 -0.2794)
							(mid -0.249642 -0.249642)
							(end -0.2794 -0.1778)
						)
						(arc
							(start -0.2794 0.1778)
							(mid -0.249642 0.249642)
							(end -0.1778 0.2794)
						)
						(arc
							(start 0.1778 0.2794)
							(mid 0.249642 0.249642)
							(end 0.2794 0.1778)
						)
						(arc
							(start 0.2794 -0.1778)
							(mid 0.249642 -0.249642)
							(end 0.1778 -0.2794)
						)
					)
					(width 0)
					(fill yes)
				)
			)
		)
	)
	(footprint ""
		(layer "F.Cu")
		(at 37.0332 -394.2842)
		(property "Reference" "PC1243"
			(at 0 0 0)
			(layer "F.SilkS")
			(hide yes)
			(effects
				(font
					(size 1.27 1.27)
				)
			)
		)
		(property "Value" "SCD01U50V2KX-1GP"
			(at 1.1811 -2.7051 0)
			(unlocked yes)
			(layer "F.Fab")
			(hide yes)
			(effects
				(font
					(size 1.016 1.016)
					(thickness 0.1524)
				)
			)
		)
		(property "Device Type" "C402H22"
			(at 1.1811 -4.2291 0)
			(unlocked yes)
			(layer "F.Fab")
			(hide yes)
			(effects
				(font
					(size 1.016 1.016)
					(thickness 0.1524)
				)
			)
		)
		(duplicate_pad_numbers_are_jumpers no)
		(fp_rect
			(start -0.4318 0.9525)
			(end 0.4318 -0.9525)
			(stroke
				(width 0)
				(type default)
			)
			(fill no)
			(layer "F.CrtYd")
		)
		(fp_rect
			(start -0.4318 0.9525)
			(end 0.4318 -0.9525)
			(stroke
				(width 0)
				(type default)
			)
			(fill no)
			(layer "F.Fab")
		)
		(pad "1" smd custom
			(at 0 -0.4445)
			(size 0.1524 0.1524)
			(layers "F.Cu" "F.Mask" "F.Paste")
			(net "P12V_SSD6")
			(options
				(clearance outline)
				(anchor circle)
			)
			(primitives
				(gr_poly
					(pts
						(arc
							(start 0.3048 -0.2032)
							(mid 0.275042 -0.275042)
							(end 0.2032 -0.3048)
						)
						(arc
							(start -0.2032 -0.3048)
							(mid -0.275042 -0.275042)
							(end -0.3048 -0.2032)
						)
						(arc
							(start -0.3048 0.2032)
							(mid -0.275042 0.275042)
							(end -0.2032 0.3048)
						)
						(arc
							(start 0.2032 0.3048)
							(mid 0.275042 0.275042)
							(end 0.3048 0.2032)
						)
					)
					(width 0)
					(fill yes)
				)
			)
		)
		(pad "2" smd custom
			(at 0 0.4445)
			(size 0.1524 0.1524)
			(layers "F.Cu" "F.Mask" "F.Paste")
			(net "GND")
			(options
				(clearance outline)
				(anchor circle)
			)
			(primitives
				(gr_poly
					(pts
						(arc
							(start 0.3048 -0.2032)
							(mid 0.275042 -0.275042)
							(end 0.2032 -0.3048)
						)
						(arc
							(start -0.2032 -0.3048)
							(mid -0.275042 -0.275042)
							(end -0.3048 -0.2032)
						)
						(arc
							(start -0.3048 0.2032)
							(mid -0.275042 0.275042)
							(end -0.2032 0.3048)
						)
						(arc
							(start 0.2032 0.3048)
							(mid 0.275042 0.275042)
							(end 0.3048 0.2032)
						)
					)
					(width 0)
					(fill yes)
				)
			)
		)
	)
)
